(kicad_pcb
	(version 20260206)
	(generator "pcbnew")
	(generator_version "10.0")
	(general
		(thickness 1.6)
		(legacy_teardrops no)
	)
	(paper "A4")
	(title_block
		(title "baseboard — 13948-1b.1110WZS1818.brd")
		(comment 1 "Honey Badger (Wiwynn) / footprints 1987-1994 of 2523")
	)
	(layers
		(0 "F.Cu" signal "TOP")
		(4 "In1.Cu" signal "L2GND")
		(6 "In2.Cu" signal "L3")
		(8 "In3.Cu" signal "L4VCC")
		(10 "In4.Cu" signal "L5VCC")
		(12 "In5.Cu" signal "L6")
		(14 "In6.Cu" signal "L7GND")
		(2 "B.Cu" signal "BOTTOM")
		(9 "F.Adhes" user "F.Adhesive")
		(11 "B.Adhes" user "B.Adhesive")
		(13 "F.Paste" user "Package Geometry/Pastemask Top")
		(15 "B.Paste" user "Package Geometry/Pastemask Bottom")
		(5 "F.SilkS" user "Ref Des/Silkscreen Top")
		(7 "B.SilkS" user "Ref Des/Silkscreen Bottom")
		(1 "F.Mask" user "Board Geometry/Soldermask Top")
		(3 "B.Mask" user "Board Geometry/Soldermask Bottom")
		(17 "Dwgs.User" user "User.Drawings")
		(19 "Cmts.User" user "User.Comments")
		(21 "Eco1.User" user "User.Eco1")
		(23 "Eco2.User" user "User.Eco2")
		(25 "Edge.Cuts" user "Board Geometry/Outline")
		(27 "Margin" user)
		(31 "F.CrtYd" user "Package Geometry/Place Bound Top")
		(29 "B.CrtYd" user "Package Geometry/Place Bound Bottom")
		(35 "F.Fab" user "Ref Des/Assembly Top")
		(33 "B.Fab" user "Ref Des/Assembly Bottom")
	)
	(footprint ""
		(layer "B.Cu")
		(at 333.375 -154.813 180)
		(property "Reference" "C3"
			(at 0 0 0)
			(layer "B.SilkS")
			(hide yes)
			(effects
				(font
					(size 1.27 1.27)
				)
				(justify mirror)
			)
		)
		(property "Value" "SCD1U16V2KX-3GP"
			(at -1.1811 -2.7051 180)
			(unlocked yes)
			(layer "B.Fab")
			(hide yes)
			(effects
				(font
					(size 1.016 1.016)
					(thickness 0.1524)
				)
				(justify mirror)
			)
		)
		(property "Device Type" "C402H22"
			(at -1.1811 -4.2291 180)
			(unlocked yes)
			(layer "B.Fab")
			(hide yes)
			(effects
				(font
					(size 1.016 1.016)
					(thickness 0.1524)
				)
				(justify mirror)
			)
		)
		(duplicate_pad_numbers_are_jumpers no)
		(fp_rect
			(start 0.4318 0.9525)
			(end -0.4318 -0.9525)
			(stroke
				(width 0)
				(type default)
			)
			(fill no)
			(layer "B.CrtYd")
		)
		(fp_rect
			(start 0.4318 0.9525)
			(end -0.4318 -0.9525)
			(stroke
				(width 0)
				(type default)
			)
			(fill no)
			(layer "B.Fab")
		)
		(pad "1" smd custom
			(at 0 -0.4445)
			(size 0.1524 0.1524)
			(layers "B.Cu" "B.Mask" "B.Paste")
			(net "P3V3_STBY")
			(options
				(clearance outline)
				(anchor circle)
			)
			(primitives
				(gr_poly
					(pts
						(arc
							(start 0.3048 0.2032)
							(mid 0.275042 0.275042)
							(end 0.2032 0.3048)
						)
						(arc
							(start -0.2032 0.3048)
							(mid -0.275042 0.275042)
							(end -0.3048 0.2032)
						)
						(arc
							(start -0.3048 -0.2032)
							(mid -0.275042 -0.275042)
							(end -0.2032 -0.3048)
						)
						(arc
							(start 0.2032 -0.3048)
							(mid 0.275042 -0.275042)
							(end 0.3048 -0.2032)
						)
					)
					(width 0)
					(fill yes)
				)
			)
		)
		(pad "2" smd custom
			(at 0 0.4445)
			(size 0.1524 0.1524)
			(layers "B.Cu" "B.Mask" "B.Paste")
			(net "GND")
			(options
				(clearance outline)
				(anchor circle)
			)
			(primitives
				(gr_poly
					(pts
						(arc
							(start 0.3048 0.2032)
							(mid 0.275042 0.275042)
							(end 0.2032 0.3048)
						)
						(arc
							(start -0.2032 0.3048)
							(mid -0.275042 0.275042)
							(end -0.3048 0.2032)
						)
						(arc
							(start -0.3048 -0.2032)
							(mid -0.275042 -0.275042)
							(end -0.2032 -0.3048)
						)
						(arc
							(start 0.2032 -0.3048)
							(mid 0.275042 -0.275042)
							(end 0.3048 -0.2032)
						)
					)
					(width 0)
					(fill yes)
				)
			)
		)
	)
	(footprint ""
		(layer "B.Cu")
		(at 129.521966 -34.29 -90)
		(property "Reference" "SR713"
			(at 0 0 90)
			(layer "B.SilkS")
			(hide yes)
			(effects
				(font
					(size 1.27 1.27)
				)
				(justify mirror)
			)
		)
		(property "Value" "10R2F-L-GP"
			(at -0.064008 -3.993896 270)
			(unlocked yes)
			(layer "B.Fab")
			(hide yes)
			(effects
				(font
					(size 1.016 1.016)
					(thickness 0.1524)
				)
				(justify mirror)
			)
		)
		(property "Device Type" "R402H14"
			(at -0.064008 -5.517896 270)
			(unlocked yes)
			(layer "B.Fab")
			(hide yes)
			(effects
				(font
					(size 1.016 1.016)
					(thickness 0.1524)
				)
				(justify mirror)
			)
		)
		(duplicate_pad_numbers_are_jumpers no)
		(fp_line
			(start -0.508 -0.9398)
			(end 0.508 -0.9398)
			(stroke
				(width 0.1524)
				(type default)
			)
			(layer "B.SilkS")
		)
		(fp_line
			(start 0.508 -0.9398)
			(end 0.508 0.9398)
			(stroke
				(width 0.1524)
				(type default)
			)
			(layer "B.SilkS")
		)
		(fp_rect
			(start 0.508 0.9398)
			(end -0.508 -0.9398)
			(stroke
				(width 0)
				(type default)
			)
			(fill no)
			(layer "B.CrtYd")
		)
		(fp_rect
			(start 0.508 0.9398)
			(end -0.508 -0.9398)
			(stroke
				(width 0)
				(type default)
			)
			(fill no)
			(layer "B.Fab")
		)
		(pad "1" smd custom
			(at 0 -0.4445 90)
			(size 0.1397 0.1397)
			(layers "B.Cu" "B.Mask" "B.Paste")
			(net "P1V8_C")
			(options
				(clearance outline)
				(anchor circle)
			)
			(primitives
				(gr_poly
					(pts
						(arc
							(start -0.1778 0.2794)
							(mid -0.249642 0.249642)
							(end -0.2794 0.1778)
						)
						(arc
							(start -0.2794 -0.1778)
							(mid -0.249642 -0.249642)
							(end -0.1778 -0.2794)
						)
						(arc
							(start 0.1778 -0.2794)
							(mid 0.249642 -0.249642)
							(end 0.2794 -0.1778)
						)
						(arc
							(start 0.2794 0.1778)
							(mid 0.249642 0.249642)
							(end 0.1778 0.2794)
						)
					)
					(width 0)
					(fill yes)
				)
			)
		)
		(pad "2" smd custom
			(at 0 0.4445 90)
			(size 0.1397 0.1397)
			(layers "B.Cu" "B.Mask" "B.Paste")
			(net "PLL_VDD")
			(options
				(clearance outline)
				(anchor circle)
			)
			(primitives
				(gr_poly
					(pts
						(arc
							(start -0.1778 0.2794)
							(mid -0.249642 0.249642)
							(end -0.2794 0.1778)
						)
						(arc
							(start -0.2794 -0.1778)
							(mid -0.249642 -0.249642)
							(end -0.1778 -0.2794)
						)
						(arc
							(start 0.1778 -0.2794)
							(mid 0.249642 -0.249642)
							(end 0.2794 -0.1778)
						)
						(arc
							(start 0.2794 0.1778)
							(mid 0.249642 0.249642)
							(end 0.1778 0.2794)
						)
					)
					(width 0)
					(fill yes)
				)
			)
		)
	)
	(footprint ""
		(layer "B.Cu")
		(at 124.34697 -109.093 180)
		(property "Reference" "SC1173"
			(at 0 0 0)
			(layer "B.SilkS")
			(hide yes)
			(effects
				(font
					(size 1.27 1.27)
				)
				(justify mirror)
			)
		)
		(property "Value" "SCD1U16V2KX-3GP"
			(at -1.1811 -2.7051 180)
			(unlocked yes)
			(layer "B.Fab")
			(hide yes)
			(effects
				(font
					(size 1.016 1.016)
					(thickness 0.1524)
				)
				(justify mirror)
			)
		)
		(property "Device Type" "C402H22"
			(at -1.1811 -4.2291 180)
			(unlocked yes)
			(layer "B.Fab")
			(hide yes)
			(effects
				(font
					(size 1.016 1.016)
					(thickness 0.1524)
				)
				(justify mirror)
			)
		)
		(duplicate_pad_numbers_are_jumpers no)
		(fp_rect
			(start 0.4318 0.9525)
			(end -0.4318 -0.9525)
			(stroke
				(width 0)
				(type default)
			)
			(fill no)
			(layer "B.CrtYd")
		)
		(fp_rect
			(start 0.4318 0.9525)
			(end -0.4318 -0.9525)
			(stroke
				(width 0)
				(type default)
			)
			(fill no)
			(layer "B.Fab")
		)
		(pad "1" smd custom
			(at 0 -0.4445)
			(size 0.1524 0.1524)
			(layers "B.Cu" "B.Mask" "B.Paste")
			(net "GB_VDDA")
			(options
				(clearance outline)
				(anchor circle)
			)
			(primitives
				(gr_poly
					(pts
						(arc
							(start 0.3048 0.2032)
							(mid 0.275042 0.275042)
							(end 0.2032 0.3048)
						)
						(arc
							(start -0.2032 0.3048)
							(mid -0.275042 0.275042)
							(end -0.3048 0.2032)
						)
						(arc
							(start -0.3048 -0.2032)
							(mid -0.275042 -0.275042)
							(end -0.2032 -0.3048)
						)
						(arc
							(start 0.2032 -0.3048)
							(mid 0.275042 -0.275042)
							(end 0.3048 -0.2032)
						)
					)
					(width 0)
					(fill yes)
				)
			)
		)
		(pad "2" smd custom
			(at 0 0.4445)
			(size 0.1524 0.1524)
			(layers "B.Cu" "B.Mask" "B.Paste")
			(net "GND")
			(options
				(clearance outline)
				(anchor circle)
			)
			(primitives
				(gr_poly
					(pts
						(arc
							(start 0.3048 0.2032)
							(mid 0.275042 0.275042)
							(end 0.2032 0.3048)
						)
						(arc
							(start -0.2032 0.3048)
							(mid -0.275042 0.275042)
							(end -0.3048 0.2032)
						)
						(arc
							(start -0.3048 -0.2032)
							(mid -0.275042 -0.275042)
							(end -0.2032 -0.3048)
						)
						(arc
							(start 0.2032 -0.3048)
							(mid 0.275042 -0.275042)
							(end 0.3048 -0.2032)
						)
					)
					(width 0)
					(fill yes)
				)
			)
		)
	)
	(footprint ""
		(layer "B.Cu")
		(at 110.852966 -49.784 -90)
		(property "Reference" "SC992"
			(at 0 0 90)
			(layer "B.SilkS")
			(hide yes)
			(effects
				(font
					(size 1.27 1.27)
				)
				(justify mirror)
			)
		)
		(property "Value" "SCD1U16V2KX-3GP"
			(at -1.1811 -2.7051 270)
			(unlocked yes)
			(layer "B.Fab")
			(hide yes)
			(effects
				(font
					(size 1.016 1.016)
					(thickness 0.1524)
				)
				(justify mirror)
			)
		)
		(property "Device Type" "C402H22"
			(at -1.1811 -4.2291 270)
			(unlocked yes)
			(layer "B.Fab")
			(hide yes)
			(effects
				(font
					(size 1.016 1.016)
					(thickness 0.1524)
				)
				(justify mirror)
			)
		)
		(duplicate_pad_numbers_are_jumpers no)
		(fp_rect
			(start 0.4318 0.9525)
			(end -0.4318 -0.9525)
			(stroke
				(width 0)
				(type default)
			)
			(fill no)
			(layer "B.CrtYd")
		)
		(fp_rect
			(start 0.4318 0.9525)
			(end -0.4318 -0.9525)
			(stroke
				(width 0)
				(type default)
			)
			(fill no)
			(layer "B.Fab")
		)
		(pad "1" smd custom
			(at 0 -0.4445 90)
			(size 0.1524 0.1524)
			(layers "B.Cu" "B.Mask" "B.Paste")
			(net "P1V8_C")
			(options
				(clearance outline)
				(anchor circle)
			)
			(primitives
				(gr_poly
					(pts
						(arc
							(start 0.3048 0.2032)
							(mid 0.275042 0.275042)
							(end 0.2032 0.3048)
						)
						(arc
							(start -0.2032 0.3048)
							(mid -0.275042 0.275042)
							(end -0.3048 0.2032)
						)
						(arc
							(start -0.3048 -0.2032)
							(mid -0.275042 -0.275042)
							(end -0.2032 -0.3048)
						)
						(arc
							(start 0.2032 -0.3048)
							(mid 0.275042 -0.275042)
							(end 0.3048 -0.2032)
						)
					)
					(width 0)
					(fill yes)
				)
			)
		)
		(pad "2" smd custom
			(at 0 0.4445 90)
			(size 0.1524 0.1524)
			(layers "B.Cu" "B.Mask" "B.Paste")
			(net "GND")
			(options
				(clearance outline)
				(anchor circle)
			)
			(primitives
				(gr_poly
					(pts
						(arc
							(start 0.3048 0.2032)
							(mid 0.275042 0.275042)
							(end 0.2032 0.3048)
						)
						(arc
							(start -0.2032 0.3048)
							(mid -0.275042 0.275042)
							(end -0.3048 0.2032)
						)
						(arc
							(start -0.3048 -0.2032)
							(mid -0.275042 -0.275042)
							(end -0.2032 -0.3048)
						)
						(arc
							(start 0.2032 -0.3048)
							(mid 0.275042 -0.275042)
							(end 0.3048 -0.2032)
						)
					)
					(width 0)
					(fill yes)
				)
			)
		)
	)
	(footprint ""
		(layer "B.Cu")
		(at 86.087966 -51.181 90)
		(property "Reference" "SC969"
			(at 0 0 90)
			(layer "B.SilkS")
			(hide yes)
			(effects
				(font
					(size 1.27 1.27)
				)
				(justify mirror)
			)
		)
		(property "Value" "SC1U10V2KX-4-GP"
			(at -1.1811 -2.7051 90)
			(unlocked yes)
			(layer "B.Fab")
			(hide yes)
			(effects
				(font
					(size 1.016 1.016)
					(thickness 0.1524)
				)
				(justify mirror)
			)
		)
		(property "Device Type" "C402H22"
			(at -1.1811 -4.2291 90)
			(unlocked yes)
			(layer "B.Fab")
			(hide yes)
			(effects
				(font
					(size 1.016 1.016)
					(thickness 0.1524)
				)
				(justify mirror)
			)
		)
		(duplicate_pad_numbers_are_jumpers no)
		(fp_rect
			(start 0.4318 0.9525)
			(end -0.4318 -0.9525)
			(stroke
				(width 0)
				(type default)
			)
			(fill no)
			(layer "B.CrtYd")
		)
		(fp_rect
			(start 0.4318 0.9525)
			(end -0.4318 -0.9525)
			(stroke
				(width 0)
				(type default)
			)
			(fill no)
			(layer "B.Fab")
		)
		(pad "1" smd custom
			(at 0 -0.4445 270)
			(size 0.1524 0.1524)
			(layers "B.Cu" "B.Mask" "B.Paste")
			(net "P1V8_C")
			(options
				(clearance outline)
				(anchor circle)
			)
			(primitives
				(gr_poly
					(pts
						(arc
							(start 0.3048 0.2032)
							(mid 0.275042 0.275042)
							(end 0.2032 0.3048)
						)
						(arc
							(start -0.2032 0.3048)
							(mid -0.275042 0.275042)
							(end -0.3048 0.2032)
						)
						(arc
							(start -0.3048 -0.2032)
							(mid -0.275042 -0.275042)
							(end -0.2032 -0.3048)
						)
						(arc
							(start 0.2032 -0.3048)
							(mid 0.275042 -0.275042)
							(end 0.3048 -0.2032)
						)
					)
					(width 0)
					(fill yes)
				)
			)
		)
		(pad "2" smd custom
			(at 0 0.4445 270)
			(size 0.1524 0.1524)
			(layers "B.Cu" "B.Mask" "B.Paste")
			(net "GND")
			(options
				(clearance outline)
				(anchor circle)
			)
			(primitives
				(gr_poly
					(pts
						(arc
							(start 0.3048 0.2032)
							(mid 0.275042 0.275042)
							(end 0.2032 0.3048)
						)
						(arc
							(start -0.2032 0.3048)
							(mid -0.275042 0.275042)
							(end -0.3048 0.2032)
						)
						(arc
							(start -0.3048 -0.2032)
							(mid -0.275042 -0.275042)
							(end -0.2032 -0.3048)
						)
						(arc
							(start 0.2032 -0.3048)
							(mid 0.275042 -0.275042)
							(end 0.3048 -0.2032)
						)
					)
					(width 0)
					(fill yes)
				)
			)
		)
	)
	(footprint ""
		(layer "B.Cu")
		(at 310.896 -182.499 90)
		(property "Reference" "SR852"
			(at 0 0 90)
			(layer "B.SilkS")
			(hide yes)
			(effects
				(font
					(size 1.27 1.27)
				)
				(justify mirror)
			)
		)
		(property "Value" "4K75R2F-1-GP"
			(at -0.064008 -3.993896 90)
			(unlocked yes)
			(layer "B.Fab")
			(hide yes)
			(effects
				(font
					(size 1.016 1.016)
					(thickness 0.1524)
				)
				(justify mirror)
			)
		)
		(property "Device Type" "R402H16"
			(at -0.064008 -5.517896 90)
			(unlocked yes)
			(layer "B.Fab")
			(hide yes)
			(effects
				(font
					(size 1.016 1.016)
					(thickness 0.1524)
				)
				(justify mirror)
			)
		)
		(duplicate_pad_numbers_are_jumpers no)
		(fp_line
			(start 0.508 -0.9398)
			(end 0.508 0.9398)
			(stroke
				(width 0.1524)
				(type default)
			)
			(layer "B.SilkS")
		)
		(fp_line
			(start -0.508 -0.9398)
			(end 0.508 -0.9398)
			(stroke
				(width 0.1524)
				(type default)
			)
			(layer "B.SilkS")
		)
		(fp_rect
			(start 0.508 0.9398)
			(end -0.508 -0.9398)
			(stroke
				(width 0)
				(type default)
			)
			(fill no)
			(layer "B.CrtYd")
		)
		(fp_rect
			(start 0.508 0.9398)
			(end -0.508 -0.9398)
			(stroke
				(width 0)
				(type default)
			)
			(fill no)
			(layer "B.Fab")
		)
		(pad "1" smd custom
			(at 0 -0.4445 270)
			(size 0.1397 0.1397)
			(layers "B.Cu" "B.Mask" "B.Paste")
			(net "BMC_FW_DET_BOARD_VER_0")
			(options
				(clearance outline)
				(anchor circle)
			)
			(primitives
				(gr_poly
					(pts
						(arc
							(start -0.1778 0.2794)
							(mid -0.249642 0.249642)
							(end -0.2794 0.1778)
						)
						(arc
							(start -0.2794 -0.1778)
							(mid -0.249642 -0.249642)
							(end -0.1778 -0.2794)
						)
						(arc
							(start 0.1778 -0.2794)
							(mid 0.249642 -0.249642)
							(end 0.2794 -0.1778)
						)
						(arc
							(start 0.2794 0.1778)
							(mid 0.249642 0.249642)
							(end 0.1778 0.2794)
						)
					)
					(width 0)
					(fill yes)
				)
			)
		)
		(pad "2" smd custom
			(at 0 0.4445 270)
			(size 0.1397 0.1397)
			(layers "B.Cu" "B.Mask" "B.Paste")
			(net "GND")
			(options
				(clearance outline)
				(anchor circle)
			)
			(primitives
				(gr_poly
					(pts
						(arc
							(start -0.1778 0.2794)
							(mid -0.249642 0.249642)
							(end -0.2794 0.1778)
						)
						(arc
							(start -0.2794 -0.1778)
							(mid -0.249642 -0.249642)
							(end -0.1778 -0.2794)
						)
						(arc
							(start 0.1778 -0.2794)
							(mid 0.249642 -0.249642)
							(end 0.2794 -0.1778)
						)
						(arc
							(start 0.2794 0.1778)
							(mid 0.249642 0.249642)
							(end 0.1778 0.2794)
						)
					)
					(width 0)
					(fill yes)
				)
			)
		)
	)
	(footprint ""
		(layer "B.Cu")
		(at 263.525 -35.814 90)
		(property "Reference" "PR48"
			(at 0 0 90)
			(layer "B.SilkS")
			(hide yes)
			(effects
				(font
					(size 1.27 1.27)
				)
				(justify mirror)
			)
		)
		(property "Value" "475KR2F-GP"
			(at -0.064008 -3.993896 90)
			(unlocked yes)
			(layer "B.Fab")
			(hide yes)
			(effects
				(font
					(size 1.016 1.016)
					(thickness 0.1524)
				)
				(justify mirror)
			)
		)
		(property "Device Type" "R402H16"
			(at -0.064008 -5.517896 90)
			(unlocked yes)
			(layer "B.Fab")
			(hide yes)
			(effects
				(font
					(size 1.016 1.016)
					(thickness 0.1524)
				)
				(justify mirror)
			)
		)
		(duplicate_pad_numbers_are_jumpers no)
		(fp_line
			(start 0.508 -0.9398)
			(end 0.508 0.9398)
			(stroke
				(width 0.1524)
				(type default)
			)
			(layer "B.SilkS")
		)
		(fp_line
			(start -0.508 -0.9398)
			(end 0.508 -0.9398)
			(stroke
				(width 0.1524)
				(type default)
			)
			(layer "B.SilkS")
		)
		(fp_rect
			(start 0.508 0.9398)
			(end -0.508 -0.9398)
			(stroke
				(width 0)
				(type default)
			)
			(fill no)
			(layer "B.CrtYd")
		)
		(fp_rect
			(start 0.508 0.9398)
			(end -0.508 -0.9398)
			(stroke
				(width 0)
				(type default)
			)
			(fill no)
			(layer "B.Fab")
		)
		(pad "1" smd custom
			(at 0 -0.4445 270)
			(size 0.1397 0.1397)
			(layers "B.Cu" "B.Mask" "B.Paste")
			(net "P1V8_STBY_MODE")
			(options
				(clearance outline)
				(anchor circle)
			)
			(primitives
				(gr_poly
					(pts
						(arc
							(start -0.1778 0.2794)
							(mid -0.249642 0.249642)
							(end -0.2794 0.1778)
						)
						(arc
							(start -0.2794 -0.1778)
							(mid -0.249642 -0.249642)
							(end -0.1778 -0.2794)
						)
						(arc
							(start 0.1778 -0.2794)
							(mid 0.249642 -0.249642)
							(end 0.2794 -0.1778)
						)
						(arc
							(start 0.2794 0.1778)
							(mid 0.249642 0.249642)
							(end 0.1778 0.2794)
						)
					)
					(width 0)
					(fill yes)
				)
			)
		)
		(pad "2" smd custom
			(at 0 0.4445 270)
			(size 0.1397 0.1397)
			(layers "B.Cu" "B.Mask" "B.Paste")
			(net "P1V8_STBY_PG")
			(options
				(clearance outline)
				(anchor circle)
			)
			(primitives
				(gr_poly
					(pts
						(arc
							(start -0.1778 0.2794)
							(mid -0.249642 0.249642)
							(end -0.2794 0.1778)
						)
						(arc
							(start -0.2794 -0.1778)
							(mid -0.249642 -0.249642)
							(end -0.1778 -0.2794)
						)
						(arc
							(start 0.1778 -0.2794)
							(mid 0.249642 -0.249642)
							(end 0.2794 -0.1778)
						)
						(arc
							(start 0.2794 0.1778)
							(mid 0.249642 0.249642)
							(end 0.1778 0.2794)
						)
					)
					(width 0)
					(fill yes)
				)
			)
		)
	)
	(footprint ""
		(layer "B.Cu")
		(at 298.069 -173.482)
		(property "Reference" "TP179"
			(at 0 0 0)
			(layer "B.SilkS")
			(hide yes)
			(effects
				(font
					(size 1.27 1.27)
				)
				(justify mirror)
			)
		)
		(property "Value" "TPAD28"
			(at 0.0127 -1.6637 0)
			(unlocked yes)
			(layer "B.Fab")
			(hide yes)
			(effects
				(font
					(size 1.016 1.016)
					(thickness 0.1524)
				)
				(justify mirror)
			)
		)
		(property "Device Type" "TPAD28"
			(at 0.0127 -3.1877 0)
			(unlocked yes)
			(layer "B.Fab")
			(hide yes)
			(effects
				(font
					(size 1.016 1.016)
					(thickness 0.1524)
				)
				(justify mirror)
			)
		)
		(duplicate_pad_numbers_are_jumpers no)
		(fp_poly
			(pts
				(arc
					(start 0.3556 0)
					(mid -0.3556 0)
					(end 0.3556 0)
				)
			)
			(stroke
				(width 0)
				(type default)
			)
			(fill no)
			(layer "B.CrtYd")
		)
		(fp_poly
			(pts
				(arc
					(start 0.6096 0)
					(mid -0.6096 0)
					(end 0.6096 0)
				)
			)
			(stroke
				(width 0)
				(type default)
			)
			(fill no)
			(layer "B.Fab")
		)
		(pad "1" smd circle
			(at 0 0 180)
			(size 0.7112 0.7112)
			(layers "B.Cu" "B.Mask" "B.Paste")
			(net "BMC0_JTAG_RTCK")
		)
	)
)
